#ISCELL
  mstr_misc dns *
  *
#ISCELL
  pure_quanta quanta_title_block_c *
  *
#ISCELL
  standard offpage *
  page44_i1
#CELL
  pure_quanta q_res *
  page44_i10
#CELL
  pure_quanta q_res *
  page44_i11
#ISCELL
  standard offpage *
  page44_i12
#ISCELL
  standard offpage *
  page44_i13
#ISCELL
  standard offpage *
  page44_i14
#ISCELL
  standard offpage *
  page44_i15
#CELL
  pure_quanta q_res *
  page44_i16
#ISCELL
  standard offpage *
  page44_i17
#ISCELL
  standard offpage *
  page44_i18
#ISCELL
  standard offpage *
  page44_i19
#ISCELL
  standard offpage *
  page44_i2
#ISCELL
  standard offpage *
  page44_i20
#ISCELL
  standard offpage *
  page44_i21
#ISCELL
  standard offpage *
  page44_i22
#ISCELL
  standard offpage *
  page44_i23
#ISCELL
  standard offpage *
  page44_i24
#ISCELL
  standard offpage *
  page44_i25
#ISCELL
  standard offpage *
  page44_i26
#ISCELL
  standard offpage *
  page44_i28
#ISCELL
  standard offpage *
  page44_i3
#ISCELL
  standard offpage *
  page44_i30
#ISCELL
  standard offpage *
  page44_i31
#ISCELL
  standard offpage *
  page44_i32
#ISCELL
  standard offpage *
  page44_i33
#ISCELL
  standard offpage *
  page44_i34
#ISCELL
  standard offpage *
  page44_i35
#ISCELL
  standard offpage *
  page44_i36
#ISCELL
  standard offpage *
  page44_i38
#ISCELL
  standard offpage *
  page44_i39
#ISCELL
  standard offpage *
  page44_i4
#ISCELL
  standard offpage *
  page44_i40
#ISCELL
  standard offpage *
  page44_i41
#ISCELL
  standard offpage *
  page44_i42
#ISCELL
  standard offpage *
  page44_i43
#ISCELL
  standard offpage *
  page44_i44
#ISCELL
  standard offpage *
  page44_i45
#ISCELL
  standard offpage *
  page44_i46
#ISCELL
  standard offpage *
  page44_i47
#ISCELL
  standard offpage *
  page44_i48
#ISCELL
  standard offpage *
  page44_i49
#ISCELL
  standard offpage *
  page44_i5
#ISCELL
  standard offpage *
  page44_i50
#CELL
  pure_quanta socket4677_azif0045p001c01cs *
  page44_i51
#ISCELL
  standard offpage *
  page44_i52
#ISCELL
  standard offpage *
  page44_i53
#ISCELL
  standard offpage *
  page44_i54
#CELL
  pure_quanta q_res *
  page44_i55
#ISCELL
  logical_power universal_gnd *
  page44_i56
#ISCELL
  standard offpage *
  page44_i57
#ISCELL
  standard offpage *
  page44_i58
#ISCELL
  standard offpage *
  page44_i6
#CELL
  pure_quanta q_res *
  page44_i7
#CELL
  pure_quanta q_res *
  page44_i8
#CELL
  pure_quanta q_res *
  page44_i9
